# T6G (Grand Teton) — schematic netlist excerpt (pin names and nets, part order shuffled) for the footprints in the layout excerpt that follows; sources: Cadence DE-HDL packaged netlist, KiCad conversion of 04192023_DAF0TMB3IC0_F0TG_MB_C_brd_V02_OCP.brd

R719  Q_RES  4.7K 5% CHIP  pkg 0201LF  page 320 : A = TEST0_RT_CPU1_P0 ; B = GND
C158  Q_CAP  10UF 25V 10% X6S  pkg C0805  page 92 : A = P12V_MEM_CPU0 ; B = GND
C126  Q_CAP  1UF 4V 20% X6S  pkg 0201  page 323 : A = P1V8_CPU1_RT0_1A ; B = GND
C1171  Q_CAP  0.1UF 16V 10% X7R  pkg C0402  page 83 : A = P3V3_AUX ; B = GND

(kicad_pcb
	(version 20260206)
	(generator "pcbnew")
	(generator_version "10.0")
	(general
		(thickness 1.6)
		(legacy_teardrops no)
	)
	(paper "A4")
	(title_block
		(title "04192023_DAF0TMB3IC0_F0TG_MB_C_brd_V02_OCP.brd")
		(comment 1 "Grand Teton / footprints 8343-8346 of 8354")
	)
	(layers
		(0 "F.Cu" signal "TOP")
		(4 "In1.Cu" signal "GND")
		(6 "In2.Cu" signal "IN1")
		(8 "In3.Cu" signal "GND1")
		(10 "In4.Cu" signal "IN2")
		(12 "In5.Cu" signal "GND2")
		(14 "In6.Cu" signal "IN3")
		(16 "In7.Cu" signal "GND3")
		(18 "In8.Cu" signal "VCC")
		(20 "In9.Cu" signal "VCC1")
		(22 "In10.Cu" signal "GND4")
		(24 "In11.Cu" signal "IN4")
		(26 "In12.Cu" signal "GND5")
		(28 "In13.Cu" signal "IN5")
		(30 "In14.Cu" signal "GND6")
		(32 "In15.Cu" signal "IN6")
		(34 "In16.Cu" signal "GND7")
		(2 "B.Cu" signal "BOTTOM")
		(9 "F.Adhes" user "F.Adhesive")
		(11 "B.Adhes" user "B.Adhesive")
		(13 "F.Paste" user "Package Geometry/Pastemask Top")
		(15 "B.Paste" user "Package Geometry/Pastemask Bottom")
		(5 "F.SilkS" user "Ref Des/Silkscreen Top")
		(7 "B.SilkS" user "Ref Des/Silkscreen Bottom")
		(1 "F.Mask" user "Board Geometry/Soldermask Top")
		(3 "B.Mask" user "Board Geometry/Soldermask Bottom")
		(17 "Dwgs.User" user "User.Drawings")
		(19 "Cmts.User" user "User.Comments")
		(21 "Eco1.User" user "User.Eco1")
		(23 "Eco2.User" user "User.Eco2")
		(25 "Edge.Cuts" user "Board Geometry/Outline")
		(27 "Margin" user)
		(31 "F.CrtYd" user "Package Geometry/Place Bound Top")
		(29 "B.CrtYd" user "Package Geometry/Place Bound Bottom")
		(35 "F.Fab" user "Ref Des/Assembly Top")
		(33 "B.Fab" user "Ref Des/Assembly Bottom")
	)
	(footprint ""
		(layer "B.Cu")
		(at 187.111894 -115.022376 180)
		(property "Reference" "C1171"
			(at 0 0 0)
			(layer "B.SilkS")
			(hide yes)
			(effects
				(font
					(size 1.27 1.27)
				)
				(justify mirror)
			)
		)
		(property "Value" ""
			(at 0 0 0)
			(layer "B.Fab")
			(effects
				(font
					(size 1.27 1.27)
				)
				(justify mirror)
			)
		)
		(duplicate_pad_numbers_are_jumpers no)
		(fp_line
			(start 0.69215 0.2921)
			(end 0.69215 -0.2921)
			(stroke
				(width 0.1524)
				(type default)
			)
			(layer "B.SilkS")
		)
		(fp_line
			(start 0.69215 -0.2921)
			(end -0.69215 -0.2921)
			(stroke
				(width 0.1524)
				(type default)
			)
			(layer "B.SilkS")
		)
		(fp_line
			(start -0.69215 0.2921)
			(end 0.69215 0.2921)
			(stroke
				(width 0.1524)
				(type default)
			)
			(layer "B.SilkS")
		)
		(fp_line
			(start -0.69215 -0.2921)
			(end -0.69215 0.2921)
			(stroke
				(width 0.1524)
				(type default)
			)
			(layer "B.SilkS")
		)
		(fp_line
			(start 0.51435 0.2794)
			(end 0.51435 -0.2794)
			(stroke
				(width 0.1)
				(type default)
			)
			(layer "B.Fab")
		)
		(fp_line
			(start 0.51435 -0.2794)
			(end -0.51435 -0.2794)
			(stroke
				(width 0.1)
				(type default)
			)
			(layer "B.Fab")
		)
		(fp_line
			(start -0.51435 0.2794)
			(end 0.51435 0.2794)
			(stroke
				(width 0.1)
				(type default)
			)
			(layer "B.Fab")
		)
		(fp_line
			(start -0.51435 -0.2794)
			(end -0.51435 0.2794)
			(stroke
				(width 0.1)
				(type default)
			)
			(layer "B.Fab")
		)
		(pad "1" smd circle
			(at 0.40005 0)
			(size 0 0)
			(layers "B.Cu" "B.Mask" "B.Paste")
			(net "P3V3_AUX")
		)
		(pad "2" smd circle
			(at -0.40005 0)
			(size 0 0)
			(layers "B.Cu" "B.Mask" "B.Paste")
			(net "GND")
		)
		(zone
			(layer "B.Cu")
			(hatch none 0.5)
			(connect_pads
				(clearance 0)
			)
			(min_thickness 0.25)
			(keepout
				(tracks not_allowed)
				(vias allowed)
				(pads allowed)
				(copperpour not_allowed)
				(footprints allowed)
			)
			(placement
				(enabled no)
				(sheetname "")
			)
			(fill
				(thermal_gap 0.5)
				(thermal_bridge_width 0.5)
				(island_removal_mode 0)
			)
			(polygon
				(pts
					(xy 186.921394 -114.934492) (xy 186.921394 -115.110006) (xy 187.012834 -115.168172) (xy 187.212224 -115.168172)
					(xy 187.302394 -115.110006) (xy 187.302394 -114.934746) (xy 187.212224 -114.876326) (xy 187.012834 -114.876326)
				)
			)
		)
	)
	(footprint ""
		(layer "B.Cu")
		(at 416.468052 -192.660016)
		(property "Reference" "C158"
			(at 0 0 0)
			(layer "B.SilkS")
			(hide yes)
			(effects
				(font
					(size 1.27 1.27)
				)
				(justify mirror)
			)
		)
		(property "Value" ""
			(at 0 0 0)
			(layer "B.Fab")
			(effects
				(font
					(size 1.27 1.27)
				)
				(justify mirror)
			)
		)
		(duplicate_pad_numbers_are_jumpers no)
		(fp_line
			(start -1.524 -0.762)
			(end -1.524 0.762)
			(stroke
				(width 0.1524)
				(type default)
			)
			(layer "B.SilkS")
		)
		(fp_line
			(start -1.524 0.762)
			(end 1.524 0.762)
			(stroke
				(width 0.1524)
				(type default)
			)
			(layer "B.SilkS")
		)
		(fp_line
			(start 1.524 -0.762)
			(end -1.524 -0.762)
			(stroke
				(width 0.1524)
				(type default)
			)
			(layer "B.SilkS")
		)
		(fp_line
			(start 1.524 0.762)
			(end 1.524 -0.762)
			(stroke
				(width 0.1524)
				(type default)
			)
			(layer "B.SilkS")
		)
		(fp_line
			(start -1.1049 -0.724916)
			(end 1.1049 -0.724916)
			(stroke
				(width 0.1)
				(type default)
			)
			(layer "B.Fab")
		)
		(fp_line
			(start -1.1049 0.724916)
			(end -1.1049 -0.724916)
			(stroke
				(width 0.1)
				(type default)
			)
			(layer "B.Fab")
		)
		(fp_line
			(start 1.1049 -0.724916)
			(end 1.1049 0.724916)
			(stroke
				(width 0.1)
				(type default)
			)
			(layer "B.Fab")
		)
		(fp_line
			(start 1.1049 0.724916)
			(end -1.1049 0.724916)
			(stroke
				(width 0.1)
				(type default)
			)
			(layer "B.Fab")
		)
		(pad "1" smd rect
			(at 0.889 0)
			(size 1.016 1.27)
			(layers "B.Cu" "B.Mask" "B.Paste")
			(net "P12V_MEM_CPU0")
		)
		(pad "2" smd rect
			(at -0.889 0)
			(size 1.016 1.27)
			(layers "B.Cu" "B.Mask" "B.Paste")
			(net "GND")
		)
	)
	(footprint ""
		(layer "B.Cu")
		(at 55.918608 -388.011162 -90)
		(property "Reference" "C126"
			(at 0 0 90)
			(layer "B.SilkS")
			(hide yes)
			(effects
				(font
					(size 1.27 1.27)
				)
				(justify mirror)
			)
		)
		(property "Value" ""
			(at 0 0 90)
			(layer "B.Fab")
			(effects
				(font
					(size 1.27 1.27)
				)
				(justify mirror)
			)
		)
		(duplicate_pad_numbers_are_jumpers no)
		(fp_line
			(start -0.299974 0.150114)
			(end 0.299974 0.150114)
			(stroke
				(width 0.1)
				(type default)
			)
			(layer "B.Fab")
		)
		(fp_line
			(start 0.299974 0.150114)
			(end 0.299974 -0.150114)
			(stroke
				(width 0.1)
				(type default)
			)
			(layer "B.Fab")
		)
		(fp_line
			(start -0.299974 -0.150114)
			(end -0.299974 0.150114)
			(stroke
				(width 0.1)
				(type default)
			)
			(layer "B.Fab")
		)
		(fp_line
			(start 0.299974 -0.150114)
			(end -0.299974 -0.150114)
			(stroke
				(width 0.1)
				(type default)
			)
			(layer "B.Fab")
		)
		(pad "1" smd rect
			(at 0.2667 0 90)
			(size 0.3048 0.381)
			(layers "B.Cu" "B.Mask" "B.Paste")
			(net "P1V8_CPU1_RT0_1A")
		)
		(pad "2" smd rect
			(at -0.2667 0 90)
			(size 0.3048 0.381)
			(layers "B.Cu" "B.Mask" "B.Paste")
			(net "GND")
		)
	)
	(footprint ""
		(layer "B.Cu")
		(at 43.265852 -385.91236 180)
		(property "Reference" "R719"
			(at 0 0 0)
			(layer "B.SilkS")
			(hide yes)
			(effects
				(font
					(size 1.27 1.27)
				)
				(justify mirror)
			)
		)
		(property "Value" ""
			(at 0 0 0)
			(layer "B.Fab")
			(effects
				(font
					(size 1.27 1.27)
				)
				(justify mirror)
			)
		)
		(duplicate_pad_numbers_are_jumpers no)
		(fp_line
			(start 0.32512 0.175006)
			(end 0.32512 -0.175006)
			(stroke
				(width 0.1)
				(type default)
			)
			(layer "B.Fab")
		)
		(fp_line
			(start 0.32512 -0.175006)
			(end -0.32512 -0.175006)
			(stroke
				(width 0.1)
				(type default)
			)
			(layer "B.Fab")
		)
		(fp_line
			(start -0.32512 0.175006)
			(end 0.32512 0.175006)
			(stroke
				(width 0.1)
				(type default)
			)
			(layer "B.Fab")
		)
		(fp_line
			(start -0.32512 -0.175006)
			(end -0.32512 0.175006)
			(stroke
				(width 0.1)
				(type default)
			)
			(layer "B.Fab")
		)
		(pad "1" smd rect
			(at 0.2667 0)
			(size 0.3048 0.381)
			(layers "B.Cu" "B.Mask" "B.Paste")
			(net "TEST0_RT_CPU1_P0")
		)
		(pad "2" smd rect
			(at -0.2667 0 180)
			(size 0.3048 0.381)
			(layers "B.Cu" "B.Mask" "B.Paste")
			(net "GND")
		)
	)
)
